(kicad_pcb
	(version 20241229)
	(generator "pcbnew")
	(generator_version "9.0")
	(general
		(thickness 1.63)
		(legacy_teardrops no)
	)
	(paper "A4")
	(title_block
		(title "CM4 Baseboard")
		(date "2026-01-05")
		(rev "1.1.1")
		(company "Antmicro Ltd")
		(comment 1 "www.antmicro.com")
		(comment 9 "footprints 417-421 of 506")
	)
	(layers
		(0 "F.Cu" signal)
		(4 "In1.Cu" power)
		(6 "In2.Cu" power)
		(8 "In3.Cu" signal)
		(10 "In4.Cu" signal)
		(2 "B.Cu" signal)
		(9 "F.Adhes" user "F.Adhesive")
		(11 "B.Adhes" user "B.Adhesive")
		(13 "F.Paste" user)
		(15 "B.Paste" user)
		(5 "F.SilkS" user "F.Silkscreen")
		(7 "B.SilkS" user "B.Silkscreen")
		(1 "F.Mask" user)
		(3 "B.Mask" user)
		(17 "Dwgs.User" user "User.Drawings")
		(19 "Cmts.User" user "User.Comments")
		(21 "Eco1.User" user "User.Eco1")
		(23 "Eco2.User" user "User.Eco2")
		(25 "Edge.Cuts" user)
		(27 "Margin" user)
		(31 "F.CrtYd" user "F.Courtyard")
		(29 "B.CrtYd" user "B.Courtyard")
		(35 "F.Fab" user)
		(33 "B.Fab" user)
	)
	(footprint "antmicro-footprints:C_0402_1005Metric"
		(layer "B.Cu")
		(at 68.837962 162.1365 180)
		(descr "Capacitor SMD 0402")
		(tags "capacitor SMD 0402")
		(property "Reference" "C309"
			(at -3.77 -0.35 0)
			(layer "B.SilkS")
			(effects
				(font
					(size 0.7 0.7)
					(thickness 0.15)
				)
				(justify left bottom mirror)
			)
		)
		(property "Value" "C_100n_0402"
			(at -1.022927 -2.155213 0)
			(layer "B.Fab")
			(effects
				(font
					(size 0.7 0.7)
					(thickness 0.15)
				)
				(justify left bottom mirror)
			)
		)
		(property "Datasheet" "https://www.murata.com/products/productdetail?partno=GRM155R61H104KE14%23"
			(at 0 0 180)
			(layer "B.Fab")
			(hide yes)
			(effects
				(font
					(size 1.27 1.27)
					(thickness 0.15)
				)
			)
		)
		(property "Manufacturer" "Murata"
			(at 0 0 180)
			(unlocked yes)
			(layer "B.Fab")
			(hide yes)
			(effects
				(font
					(size 1 1)
					(thickness 0.15)
				)
				(justify mirror)
			)
		)
		(property "MPN" "GRM155R61H104KE14D"
			(at 0 0 180)
			(unlocked yes)
			(layer "B.Fab")
			(hide yes)
			(effects
				(font
					(size 1 1)
					(thickness 0.15)
				)
				(justify mirror)
			)
		)
		(property "Val" "100n"
			(at 0 0 180)
			(unlocked yes)
			(layer "B.Fab")
			(hide yes)
			(effects
				(font
					(size 1 1)
					(thickness 0.15)
				)
				(justify mirror)
			)
		)
		(property "License" "Apache-2.0"
			(at 0 0 180)
			(unlocked yes)
			(layer "B.Fab")
			(hide yes)
			(effects
				(font
					(size 1 1)
					(thickness 0.15)
				)
				(justify mirror)
			)
		)
		(property "Author" "Antmicro"
			(at 0 0 180)
			(unlocked yes)
			(layer "B.Fab")
			(hide yes)
			(effects
				(font
					(size 1 1)
					(thickness 0.15)
				)
				(justify mirror)
			)
		)
		(property "Voltage" "50V"
			(at 0 0 180)
			(unlocked yes)
			(layer "B.Fab")
			(hide yes)
			(effects
				(font
					(size 1 1)
					(thickness 0.15)
				)
				(justify mirror)
			)
		)
		(property "Dielectric" "X5R"
			(at 0 0 180)
			(unlocked yes)
			(layer "B.Fab")
			(hide yes)
			(effects
				(font
					(size 1 1)
					(thickness 0.15)
				)
				(justify mirror)
			)
		)
		(sheetname "/Supply/")
		(sheetfile "supply.kicad_sch")
		(attr smd)
		(fp_rect
			(start -0.925 0.47)
			(end 0.925 -0.47)
			(stroke
				(width 0.05)
				(type default)
			)
			(fill no)
			(layer "B.CrtYd")
		)
		(fp_line
			(start 0.504 0.25)
			(end 0.504 -0.248)
			(stroke
				(width 0.15)
				(type solid)
			)
			(layer "B.Fab")
		)
		(fp_line
			(start 0.504 -0.248)
			(end -0.494 -0.248)
			(stroke
				(width 0.15)
				(type solid)
			)
			(layer "B.Fab")
		)
		(fp_line
			(start -0.494 0.25)
			(end 0.504 0.25)
			(stroke
				(width 0.15)
				(type solid)
			)
			(layer "B.Fab")
		)
		(fp_line
			(start -0.494 -0.248)
			(end -0.494 0.25)
			(stroke
				(width 0.15)
				(type solid)
			)
			(layer "B.Fab")
		)
		(fp_text user "License: Apache-2.0"
			(at -0.939 -5.799 0)
			(layer "B.Fab")
			(effects
				(font
					(size 0.7 0.7)
					(thickness 0.15)
				)
				(justify left bottom mirror)
			)
		)
		(fp_text user "${REFERENCE}"
			(at -0.939 -4.599 0)
			(layer "B.Fab")
			(effects
				(font
					(size 0.7 0.7)
					(thickness 0.15)
				)
				(justify left bottom mirror)
			)
		)
		(fp_text user "Author: Antmicro"
			(at -0.939 -3.399 0)
			(layer "B.Fab")
			(effects
				(font
					(size 0.7 0.7)
					(thickness 0.15)
				)
				(justify left bottom mirror)
			)
		)
		(pad "1" smd roundrect
			(at -0.48 0 180)
			(size 0.59 0.64)
			(layers "B.Cu" "B.Mask" "B.Paste")
			(roundrect_rratio 0.25)
			(net 49 "/Supply/SW_3V3")
			(pintype "passive")
		)
		(pad "2" smd roundrect
			(at 0.48 0 180)
			(size 0.59 0.64)
			(layers "B.Cu" "B.Mask" "B.Paste")
			(roundrect_rratio 0.25)
			(net 51 "Net-(U302-BST)")
			(pintype "passive")
		)
	)
	(footprint "antmicro-footprints:C_0805_2012Metric"
		(layer "B.Cu")
		(at 84.667962 127.1165 -90)
		(descr "Capacitor SMD 0805")
		(tags "capacitor SMD 0805")
		(property "Reference" "C905"
			(at 1.81 -0.24 90)
			(layer "B.SilkS")
			(effects
				(font
					(size 0.7 0.7)
					(thickness 0.15)
				)
				(justify left bottom mirror)
			)
		)
		(property "Value" "C_22u_25V_0805"
			(at -2.055717 -1.963152 90)
			(layer "B.Fab")
			(effects
				(font
					(size 0.7 0.7)
					(thickness 0.15)
				)
				(justify left bottom mirror)
			)
		)
		(property "Datasheet" "https://product.samsungsem.com/mlcc/CL21A226MAYNNN.do"
			(at 0 0 270)
			(layer "B.Fab")
			(hide yes)
			(effects
				(font
					(size 1.27 1.27)
					(thickness 0.15)
				)
			)
		)
		(property "Manufacturer" "Samsung Electro-Mechanics"
			(at 0 0 270)
			(unlocked yes)
			(layer "B.Fab")
			(hide yes)
			(effects
				(font
					(size 1 1)
					(thickness 0.15)
				)
				(justify mirror)
			)
		)
		(property "MPN" "CL21A226MAYNNNE"
			(at 0 0 270)
			(unlocked yes)
			(layer "B.Fab")
			(hide yes)
			(effects
				(font
					(size 1 1)
					(thickness 0.15)
				)
				(justify mirror)
			)
		)
		(property "Val" "22u"
			(at 0 0 270)
			(unlocked yes)
			(layer "B.Fab")
			(hide yes)
			(effects
				(font
					(size 1 1)
					(thickness 0.15)
				)
				(justify mirror)
			)
		)
		(property "License" "Apache-2.0"
			(at 0 0 270)
			(unlocked yes)
			(layer "B.Fab")
			(hide yes)
			(effects
				(font
					(size 1 1)
					(thickness 0.15)
				)
				(justify mirror)
			)
		)
		(property "Author" "Antmicro"
			(at 0 0 270)
			(unlocked yes)
			(layer "B.Fab")
			(hide yes)
			(effects
				(font
					(size 1 1)
					(thickness 0.15)
				)
				(justify mirror)
			)
		)
		(property "Voltage" "25V"
			(at 0 0 270)
			(unlocked yes)
			(layer "B.Fab")
			(hide yes)
			(effects
				(font
					(size 1 1)
					(thickness 0.15)
				)
				(justify mirror)
			)
		)
		(property "Dielectric" "X5R"
			(at 0 0 270)
			(unlocked yes)
			(layer "B.Fab")
			(hide yes)
			(effects
				(font
					(size 1 1)
					(thickness 0.15)
				)
				(justify mirror)
			)
		)
		(property "Public" "False"
			(at 0 0 270)
			(unlocked yes)
			(layer "B.Fab")
			(hide yes)
			(effects
				(font
					(size 1 1)
					(thickness 0.15)
				)
				(justify mirror)
			)
		)
		(sheetname "/USB/")
		(sheetfile "usb.kicad_sch")
		(attr smd)
		(fp_line
			(start -0.3 0.7)
			(end 0.3 0.7)
			(stroke
				(width 0.15)
				(type solid)
			)
			(layer "B.SilkS")
		)
		(fp_line
			(start -0.3 -0.7)
			(end 0.3 -0.7)
			(stroke
				(width 0.15)
				(type solid)
			)
			(layer "B.SilkS")
		)
		(fp_rect
			(start 1.95 0.9)
			(end -1.95 -0.9)
			(stroke
				(width 0.05)
				(type default)
			)
			(fill no)
			(layer "B.CrtYd")
		)
		(fp_rect
			(start -0.95 0.675)
			(end 0.95 -0.675)
			(stroke
				(width 0.15)
				(type solid)
			)
			(fill no)
			(layer "B.Fab")
		)
		(fp_text user "${REFERENCE}"
			(at -1.9 -3.947 90)
			(layer "B.Fab")
			(effects
				(font
					(size 0.7 0.7)
					(thickness 0.15)
				)
				(justify left bottom mirror)
			)
		)
		(fp_text user "Author: Antmicro"
			(at -1.9 -5.947 90)
			(layer "B.Fab")
			(effects
				(font
					(size 0.7 0.7)
					(thickness 0.15)
				)
				(justify left bottom mirror)
			)
		)
		(fp_text user "License: Apache-2.0"
			(at -1.9 -4.947 90)
			(layer "B.Fab")
			(effects
				(font
					(size 0.7 0.7)
					(thickness 0.15)
				)
				(justify left bottom mirror)
			)
		)
		(pad "1" smd roundrect
			(at -1.1 0 270)
			(size 1.2 1.3)
			(layers "B.Cu" "B.Mask" "B.Paste")
			(roundrect_rratio 0.25)
			(net 26 "/USB/USBD_VBUS")
			(pintype "passive")
		)
		(pad "2" smd roundrect
			(at 1.1 0 270)
			(size 1.2 1.3)
			(layers "B.Cu" "B.Mask" "B.Paste")
			(roundrect_rratio 0.25)
			(net 3 "GND")
			(pintype "passive")
		)
	)
	(footprint "antmicro-footprints:R_0402_1005Metric"
		(layer "B.Cu")
		(at 52.842962 158.4265)
		(descr "Resistor SMD 0402")
		(tags "resistor SMD 0402")
		(property "Reference" "R317"
			(at -4.215 1.07 0)
			(layer "B.SilkS")
			(effects
				(font
					(size 0.7 0.7)
					(thickness 0.15)
				)
				(justify right bottom mirror)
			)
		)
		(property "Value" "R_2k_0402"
			(at -1.011843 -1.772047 0)
			(layer "B.Fab")
			(effects
				(font
					(size 0.7 0.7)
					(thickness 0.15)
				)
				(justify right bottom mirror)
			)
		)
		(property "Datasheet" "https://www.bourns.com/docs/product-datasheets/cr.pdf"
			(at 0 0 0)
			(layer "B.Fab")
			(hide yes)
			(effects
				(font
					(size 1.27 1.27)
					(thickness 0.15)
				)
			)
		)
		(property "MPN" "CR0402-FX-2001GLF"
			(at 0 0 0)
			(unlocked yes)
			(layer "B.Fab")
			(hide yes)
			(effects
				(font
					(size 1 1)
					(thickness 0.15)
				)
				(justify mirror)
			)
		)
		(property "Manufacturer" "Bourns"
			(at 0 0 0)
			(unlocked yes)
			(layer "B.Fab")
			(hide yes)
			(effects
				(font
					(size 1 1)
					(thickness 0.15)
				)
				(justify mirror)
			)
		)
		(property "License" "Apache-2.0"
			(at 0 0 0)
			(unlocked yes)
			(layer "B.Fab")
			(hide yes)
			(effects
				(font
					(size 1 1)
					(thickness 0.15)
				)
				(justify mirror)
			)
		)
		(property "Author" "Antmicro"
			(at 0 0 0)
			(unlocked yes)
			(layer "B.Fab")
			(hide yes)
			(effects
				(font
					(size 1 1)
					(thickness 0.15)
				)
				(justify mirror)
			)
		)
		(property "Val" "2k"
			(at 0 0 0)
			(unlocked yes)
			(layer "B.Fab")
			(hide yes)
			(effects
				(font
					(size 1 1)
					(thickness 0.15)
				)
				(justify mirror)
			)
		)
		(property "Tolerance" "1%"
			(at 0 0 0)
			(unlocked yes)
			(layer "B.Fab")
			(hide yes)
			(effects
				(font
					(size 1 1)
					(thickness 0.15)
				)
				(justify mirror)
			)
		)
		(sheetname "/Supply/")
		(sheetfile "supply.kicad_sch")
		(attr smd)
		(fp_rect
			(start -0.925 0.47)
			(end 0.925 -0.47)
			(stroke
				(width 0.05)
				(type default)
			)
			(fill no)
			(layer "B.CrtYd")
		)
		(fp_rect
			(start -0.5 0.25)
			(end 0.5 -0.25)
			(stroke
				(width 0.15)
				(type solid)
			)
			(fill no)
			(layer "B.Fab")
		)
		(fp_text user "${REFERENCE}"
			(at -0.95 -3.168 180)
			(layer "B.Fab")
			(effects
				(font
					(size 0.7 0.7)
					(thickness 0.15)
				)
				(justify left bottom mirror)
			)
		)
		(fp_text user "Author: Antmicro"
			(at -0.95 -4.169 180)
			(layer "B.Fab")
			(effects
				(font
					(size 0.7 0.7)
					(thickness 0.15)
				)
				(justify left bottom mirror)
			)
		)
		(fp_text user "License: Apache-2.0"
			(at -0.95 -5.169 180)
			(layer "B.Fab")
			(effects
				(font
					(size 0.7 0.7)
					(thickness 0.15)
				)
				(justify left bottom mirror)
			)
		)
		(pad "1" smd roundrect
			(at -0.48 0)
			(size 0.59 0.64)
			(layers "B.Cu" "B.Mask" "B.Paste")
			(roundrect_rratio 0.25)
			(net 3 "GND")
			(pintype "passive")
		)
		(pad "2" smd roundrect
			(at 0.48 0)
			(size 0.59 0.64)
			(layers "B.Cu" "B.Mask" "B.Paste")
			(roundrect_rratio 0.25)
			(net 353 "/Supply/FB_5V")
			(pintype "passive")
		)
	)
	(footprint "antmicro-footprints:C_0805_2012Metric"
		(layer "B.Cu")
		(at 58.617962 171.3165 -90)
		(descr "Capacitor SMD 0805")
		(tags "capacitor SMD 0805")
		(property "Reference" "C409"
			(at 1.76 -0.4 90)
			(layer "B.SilkS")
			(effects
				(font
					(size 0.7 0.7)
					(thickness 0.15)
				)
				(justify left bottom mirror)
			)
		)
		(property "Value" "C_22u_25V_0805"
			(at -2.055717 -1.963152 90)
			(layer "B.Fab")
			(effects
				(font
					(size 0.7 0.7)
					(thickness 0.15)
				)
				(justify left bottom mirror)
			)
		)
		(property "Datasheet" "https://product.samsungsem.com/mlcc/CL21A226MAYNNN.do"
			(at 0 0 270)
			(layer "B.Fab")
			(hide yes)
			(effects
				(font
					(size 1.27 1.27)
					(thickness 0.15)
				)
			)
		)
		(property "Manufacturer" "Samsung Electro-Mechanics"
			(at 0 0 270)
			(unlocked yes)
			(layer "B.Fab")
			(hide yes)
			(effects
				(font
					(size 1 1)
					(thickness 0.15)
				)
				(justify mirror)
			)
		)
		(property "MPN" "CL21A226MAYNNNE"
			(at 0 0 270)
			(unlocked yes)
			(layer "B.Fab")
			(hide yes)
			(effects
				(font
					(size 1 1)
					(thickness 0.15)
				)
				(justify mirror)
			)
		)
		(property "Val" "22u"
			(at 0 0 270)
			(unlocked yes)
			(layer "B.Fab")
			(hide yes)
			(effects
				(font
					(size 1 1)
					(thickness 0.15)
				)
				(justify mirror)
			)
		)
		(property "License" "Apache-2.0"
			(at 0 0 270)
			(unlocked yes)
			(layer "B.Fab")
			(hide yes)
			(effects
				(font
					(size 1 1)
					(thickness 0.15)
				)
				(justify mirror)
			)
		)
		(property "Author" "Antmicro"
			(at 0 0 270)
			(unlocked yes)
			(layer "B.Fab")
			(hide yes)
			(effects
				(font
					(size 1 1)
					(thickness 0.15)
				)
				(justify mirror)
			)
		)
		(property "Voltage" "25V"
			(at 0 0 270)
			(unlocked yes)
			(layer "B.Fab")
			(hide yes)
			(effects
				(font
					(size 1 1)
					(thickness 0.15)
				)
				(justify mirror)
			)
		)
		(property "Dielectric" "X5R"
			(at 0 0 270)
			(unlocked yes)
			(layer "B.Fab")
			(hide yes)
			(effects
				(font
					(size 1 1)
					(thickness 0.15)
				)
				(justify mirror)
			)
		)
		(property "Public" "False"
			(at 0 0 270)
			(unlocked yes)
			(layer "B.Fab")
			(hide yes)
			(effects
				(font
					(size 1 1)
					(thickness 0.15)
				)
				(justify mirror)
			)
		)
		(sheetname "/Ethernet/")
		(sheetfile "ethernet.kicad_sch")
		(attr smd)
		(fp_line
			(start -0.3 0.7)
			(end 0.3 0.7)
			(stroke
				(width 0.15)
				(type solid)
			)
			(layer "B.SilkS")
		)
		(fp_line
			(start -0.3 -0.7)
			(end 0.3 -0.7)
			(stroke
				(width 0.15)
				(type solid)
			)
			(layer "B.SilkS")
		)
		(fp_rect
			(start 1.95 0.9)
			(end -1.95 -0.9)
			(stroke
				(width 0.05)
				(type default)
			)
			(fill no)
			(layer "B.CrtYd")
		)
		(fp_rect
			(start -0.95 0.675)
			(end 0.95 -0.675)
			(stroke
				(width 0.15)
				(type solid)
			)
			(fill no)
			(layer "B.Fab")
		)
		(fp_text user "Author: Antmicro"
			(at -1.9 -5.947 90)
			(layer "B.Fab")
			(effects
				(font
					(size 0.7 0.7)
					(thickness 0.15)
				)
				(justify left bottom mirror)
			)
		)
		(fp_text user "License: Apache-2.0"
			(at -1.9 -4.947 90)
			(layer "B.Fab")
			(effects
				(font
					(size 0.7 0.7)
					(thickness 0.15)
				)
				(justify left bottom mirror)
			)
		)
		(fp_text user "${REFERENCE}"
			(at -1.9 -3.947 90)
			(layer "B.Fab")
			(effects
				(font
					(size 0.7 0.7)
					(thickness 0.15)
				)
				(justify left bottom mirror)
			)
		)
		(pad "1" smd roundrect
			(at -1.1 0 270)
			(size 1.2 1.3)
			(layers "B.Cu" "B.Mask" "B.Paste")
			(roundrect_rratio 0.25)
			(net 47 "/Ethernet/POE_12V")
			(pintype "passive")
		)
		(pad "2" smd roundrect
			(at 1.1 0 270)
			(size 1.2 1.3)
			(layers "B.Cu" "B.Mask" "B.Paste")
			(roundrect_rratio 0.25)
			(net 3 "GND")
			(pintype "passive")
		)
	)
	(footprint "antmicro-footprints:C_0805_2012Metric"
		(layer "B.Cu")
		(at 107.617962 135.9365 -90)
		(descr "Capacitor SMD 0805")
		(tags "capacitor SMD 0805")
		(property "Reference" "C305"
			(at -0.1 1.12 90)
			(layer "B.SilkS")
			(effects
				(font
					(size 0.7 0.7)
					(thickness 0.15)
				)
				(justify left bottom mirror)
			)
		)
		(property "Value" "C_22u_25V_0805"
			(at -2.055717 -1.963152 90)
			(layer "B.Fab")
			(effects
				(font
					(size 0.7 0.7)
					(thickness 0.15)
				)
				(justify left bottom mirror)
			)
		)
		(property "Datasheet" "https://product.samsungsem.com/mlcc/CL21A226MAYNNN.do"
			(at 0 0 270)
			(layer "B.Fab")
			(hide yes)
			(effects
				(font
					(size 1.27 1.27)
					(thickness 0.15)
				)
			)
		)
		(property "Manufacturer" "Samsung Electro-Mechanics"
			(at 0 0 270)
			(unlocked yes)
			(layer "B.Fab")
			(hide yes)
			(effects
				(font
					(size 1 1)
					(thickness 0.15)
				)
				(justify mirror)
			)
		)
		(property "MPN" "CL21A226MAYNNNE"
			(at 0 0 270)
			(unlocked yes)
			(layer "B.Fab")
			(hide yes)
			(effects
				(font
					(size 1 1)
					(thickness 0.15)
				)
				(justify mirror)
			)
		)
		(property "Val" "22u"
			(at 0 0 270)
			(unlocked yes)
			(layer "B.Fab")
			(hide yes)
			(effects
				(font
					(size 1 1)
					(thickness 0.15)
				)
				(justify mirror)
			)
		)
		(property "License" "Apache-2.0"
			(at 0 0 270)
			(unlocked yes)
			(layer "B.Fab")
			(hide yes)
			(effects
				(font
					(size 1 1)
					(thickness 0.15)
				)
				(justify mirror)
			)
		)
		(property "Author" "Antmicro"
			(at 0 0 270)
			(unlocked yes)
			(layer "B.Fab")
			(hide yes)
			(effects
				(font
					(size 1 1)
					(thickness 0.15)
				)
				(justify mirror)
			)
		)
		(property "Voltage" "25V"
			(at 0 0 270)
			(unlocked yes)
			(layer "B.Fab")
			(hide yes)
			(effects
				(font
					(size 1 1)
					(thickness 0.15)
				)
				(justify mirror)
			)
		)
		(property "Dielectric" "X5R"
			(at 0 0 270)
			(unlocked yes)
			(layer "B.Fab")
			(hide yes)
			(effects
				(font
					(size 1 1)
					(thickness 0.15)
				)
				(justify mirror)
			)
		)
		(property "Public" "False"
			(at 0 0 270)
			(unlocked yes)
			(layer "B.Fab")
			(hide yes)
			(effects
				(font
					(size 1 1)
					(thickness 0.15)
				)
				(justify mirror)
			)
		)
		(sheetname "/Supply/")
		(sheetfile "supply.kicad_sch")
		(attr smd)
		(fp_line
			(start -0.3 0.7)
			(end 0.3 0.7)
			(stroke
				(width 0.15)
				(type solid)
			)
			(layer "B.SilkS")
		)
		(fp_line
			(start -0.3 -0.7)
			(end 0.3 -0.7)
			(stroke
				(width 0.15)
				(type solid)
			)
			(layer "B.SilkS")
		)
		(fp_rect
			(start 1.95 0.9)
			(end -1.95 -0.9)
			(stroke
				(width 0.05)
				(type default)
			)
			(fill no)
			(layer "B.CrtYd")
		)
		(fp_rect
			(start -0.95 0.675)
			(end 0.95 -0.675)
			(stroke
				(width 0.15)
				(type solid)
			)
			(fill no)
			(layer "B.Fab")
		)
		(fp_text user "${REFERENCE}"
			(at -1.9 -3.947 90)
			(layer "B.Fab")
			(effects
				(font
					(size 0.7 0.7)
					(thickness 0.15)
				)
				(justify left bottom mirror)
			)
		)
		(fp_text user "Author: Antmicro"
			(at -1.9 -5.947 90)
			(layer "B.Fab")
			(effects
				(font
					(size 0.7 0.7)
					(thickness 0.15)
				)
				(justify left bottom mirror)
			)
		)
		(fp_text user "License: Apache-2.0"
			(at -1.9 -4.947 90)
			(layer "B.Fab")
			(effects
				(font
					(size 0.7 0.7)
					(thickness 0.15)
				)
				(justify left bottom mirror)
			)
		)
		(pad "1" smd roundrect
			(at -1.1 0 270)
			(size 1.2 1.3)
			(layers "B.Cu" "B.Mask" "B.Paste")
			(roundrect_rratio 0.25)
			(net 43 "VCC")
			(pintype "passive")
		)
		(pad "2" smd roundrect
			(at 1.1 0 270)
			(size 1.2 1.3)
			(layers "B.Cu" "B.Mask" "B.Paste")
			(roundrect_rratio 0.25)
			(net 3 "GND")
			(pintype "passive")
		)
	)
)
